#ISCELL
  mstr_misc prelim *
  *
#ISCELL
  mstr_symbols design_note *
  *
#ISCELL
  mstr_symbols intel_corp_bpage *
  *
#CELL
  chpset_lib skx_ext_b *
  page70_i10
#ISCELL
  mstr_standard offpage *
  page70_i11
#ISCELL
  mstr_symbols vcc_core *
  page70_i12
#ISCELL
  mstr_symbols vcc_core *
  page70_i13
#ISCELL
  mstr_symbols vcc_core *
  page70_i15
#ISCELL
  mstr_symbols vcc_core *
  page70_i16
#ISCELL
  mstr_standard offpage *
  page70_i7
#CELL
  chpset_lib skx_ext_b *
  page70_i9
